(kicad_pcb
	(version 20260206)
	(generator "pcbnew")
	(generator_version "10.0")
	(general
		(thickness 1.6)
		(legacy_teardrops no)
	)
	(paper "A4")
	(title_block
		(title "01162023_DA0F0TEBIF0_F0T_Expander_BD_F_brd_V02_OCP.brd")
		(comment 1 "Grand Teton / footprints 4329-4335 of 9728")
	)
	(layers
		(0 "F.Cu" signal "TOP")
		(4 "In1.Cu" signal "GND")
		(6 "In2.Cu" signal "VCC")
		(8 "In3.Cu" signal "VCC1")
		(10 "In4.Cu" signal "GND1")
		(12 "In5.Cu" signal "IN1")
		(14 "In6.Cu" signal "GND2")
		(16 "In7.Cu" signal "IN2")
		(18 "In8.Cu" signal "GND3")
		(20 "In9.Cu" signal "IN3")
		(22 "In10.Cu" signal "GND4")
		(24 "In11.Cu" signal "IN4")
		(26 "In12.Cu" signal "GND5")
		(28 "In13.Cu" signal "IN5")
		(30 "In14.Cu" signal "GND6")
		(32 "In15.Cu" signal "IN6")
		(34 "In16.Cu" signal "GND7")
		(2 "B.Cu" signal "BOTTOM")
		(9 "F.Adhes" user "F.Adhesive")
		(11 "B.Adhes" user "B.Adhesive")
		(13 "F.Paste" user "Package Geometry/Pastemask Top")
		(15 "B.Paste" user "Package Geometry/Pastemask Bottom")
		(5 "F.SilkS" user "Ref Des/Silkscreen Top")
		(7 "B.SilkS" user "Ref Des/Silkscreen Bottom")
		(1 "F.Mask" user "Board Geometry/Soldermask Top")
		(3 "B.Mask" user "Board Geometry/Soldermask Bottom")
		(17 "Dwgs.User" user "User.Drawings")
		(19 "Cmts.User" user "User.Comments")
		(21 "Eco1.User" user "User.Eco1")
		(23 "Eco2.User" user "User.Eco2")
		(25 "Edge.Cuts" user "Board Geometry/Outline")
		(27 "Margin" user)
		(31 "F.CrtYd" user "Package Geometry/Place Bound Top")
		(29 "B.CrtYd" user "Package Geometry/Place Bound Bottom")
		(35 "F.Fab" user "Ref Des/Assembly Top")
		(33 "B.Fab" user "Ref Des/Assembly Bottom")
	)
	(footprint ""
		(layer "F.Cu")
		(at 370.327936 -35.876738)
		(property "Reference" "R6107"
			(at 0 0 0)
			(layer "F.SilkS")
			(hide yes)
			(effects
				(font
					(size 1.27 1.27)
				)
			)
		)
		(property "Value" ""
			(at 0 0 0)
			(layer "F.Fab")
			(effects
				(font
					(size 1.27 1.27)
				)
			)
		)
		(duplicate_pad_numbers_are_jumpers no)
		(fp_line
			(start -0.7874 -0.4064)
			(end 0.7874 -0.4064)
			(stroke
				(width 0.1524)
				(type default)
			)
			(layer "F.SilkS")
		)
		(fp_line
			(start -0.7874 0.4064)
			(end -0.7874 -0.4064)
			(stroke
				(width 0.1524)
				(type default)
			)
			(layer "F.SilkS")
		)
		(fp_line
			(start 0.7874 -0.4064)
			(end 0.7874 0.4064)
			(stroke
				(width 0.1524)
				(type default)
			)
			(layer "F.SilkS")
		)
		(fp_line
			(start 0.7874 0.4064)
			(end -0.7874 0.4064)
			(stroke
				(width 0.1524)
				(type default)
			)
			(layer "F.SilkS")
		)
		(fp_line
			(start -0.67945 -0.305054)
			(end -0.12065 -0.305054)
			(stroke
				(width 0.1)
				(type default)
			)
			(layer "F.Fab")
		)
		(fp_line
			(start -0.67945 0.3048)
			(end -0.67945 -0.305054)
			(stroke
				(width 0.1)
				(type default)
			)
			(layer "F.Fab")
		)
		(fp_line
			(start -0.12065 -0.305054)
			(end -0.12065 -0.2794)
			(stroke
				(width 0.1)
				(type default)
			)
			(layer "F.Fab")
		)
		(fp_line
			(start -0.12065 -0.2794)
			(end 0.12065 -0.2794)
			(stroke
				(width 0.1)
				(type default)
			)
			(layer "F.Fab")
		)
		(fp_line
			(start -0.12065 0.2794)
			(end -0.12065 0.3048)
			(stroke
				(width 0.1)
				(type default)
			)
			(layer "F.Fab")
		)
		(fp_line
			(start -0.12065 0.3048)
			(end -0.67945 0.3048)
			(stroke
				(width 0.1)
				(type default)
			)
			(layer "F.Fab")
		)
		(fp_line
			(start 0.120396 0.2794)
			(end -0.12065 0.2794)
			(stroke
				(width 0.1)
				(type default)
			)
			(layer "F.Fab")
		)
		(fp_line
			(start 0.120396 0.3048)
			(end 0.120396 0.2794)
			(stroke
				(width 0.1)
				(type default)
			)
			(layer "F.Fab")
		)
		(fp_line
			(start 0.12065 -0.3048)
			(end 0.67945 -0.3048)
			(stroke
				(width 0.1)
				(type default)
			)
			(layer "F.Fab")
		)
		(fp_line
			(start 0.12065 -0.2794)
			(end 0.12065 -0.3048)
			(stroke
				(width 0.1)
				(type default)
			)
			(layer "F.Fab")
		)
		(fp_line
			(start 0.67945 -0.3048)
			(end 0.67945 0.3048)
			(stroke
				(width 0.1)
				(type default)
			)
			(layer "F.Fab")
		)
		(fp_line
			(start 0.67945 0.3048)
			(end 0.120396 0.3048)
			(stroke
				(width 0.1)
				(type default)
			)
			(layer "F.Fab")
		)
		(pad "1" smd circle
			(at -0.40005 0)
			(size 0 0)
			(layers "F.Cu" "F.Mask" "F.Paste")
			(net "PWRGD_P3V3_SSD13_D")
		)
		(pad "2" smd circle
			(at 0.40005 0)
			(size 0 0)
			(layers "F.Cu" "F.Mask" "F.Paste")
			(net "PWRGD_P3V3_SSD13_R")
		)
	)
	(footprint ""
		(layer "F.Cu")
		(at 418.13988 -70.52437 90)
		(property "Reference" "PC431"
			(at 0 0 90)
			(layer "F.SilkS")
			(hide yes)
			(effects
				(font
					(size 1.27 1.27)
				)
			)
		)
		(property "Value" ""
			(at 0 0 90)
			(layer "F.Fab")
			(effects
				(font
					(size 1.27 1.27)
				)
			)
		)
		(duplicate_pad_numbers_are_jumpers no)
		(fp_line
			(start 1.524 -0.762)
			(end 1.524 0.762)
			(stroke
				(width 0.1524)
				(type default)
			)
			(layer "F.SilkS")
		)
		(fp_line
			(start -1.524 -0.762)
			(end 1.524 -0.762)
			(stroke
				(width 0.1524)
				(type default)
			)
			(layer "F.SilkS")
		)
		(fp_line
			(start 1.524 0.762)
			(end -1.524 0.762)
			(stroke
				(width 0.1524)
				(type default)
			)
			(layer "F.SilkS")
		)
		(fp_line
			(start -1.524 0.762)
			(end -1.524 -0.762)
			(stroke
				(width 0.1524)
				(type default)
			)
			(layer "F.SilkS")
		)
		(fp_line
			(start 1.1049 -0.724916)
			(end -1.1049 -0.724916)
			(stroke
				(width 0.1)
				(type default)
			)
			(layer "F.Fab")
		)
		(fp_line
			(start -1.1049 -0.724916)
			(end -1.1049 0.724916)
			(stroke
				(width 0.1)
				(type default)
			)
			(layer "F.Fab")
		)
		(fp_line
			(start 1.1049 0.724916)
			(end 1.1049 -0.724916)
			(stroke
				(width 0.1)
				(type default)
			)
			(layer "F.Fab")
		)
		(fp_line
			(start -1.1049 0.724916)
			(end 1.1049 0.724916)
			(stroke
				(width 0.1)
				(type default)
			)
			(layer "F.Fab")
		)
		(pad "1" smd rect
			(at -0.889 0 270)
			(size 1.016 1.27)
			(layers "F.Cu" "F.Mask" "F.Paste")
			(net "P12V_SSD14_R")
		)
		(pad "2" smd rect
			(at 0.889 0 270)
			(size 1.016 1.27)
			(layers "F.Cu" "F.Mask" "F.Paste")
			(net "GND")
		)
	)
	(footprint ""
		(layer "F.Cu")
		(at 140.259816 -214.982806 180)
		(property "Reference" "C2596"
			(at 0 0 180)
			(layer "F.SilkS")
			(hide yes)
			(effects
				(font
					(size 1.27 1.27)
				)
			)
		)
		(property "Value" ""
			(at 0 0 180)
			(layer "F.Fab")
			(effects
				(font
					(size 1.27 1.27)
				)
			)
		)
		(duplicate_pad_numbers_are_jumpers no)
		(fp_line
			(start 1.2954 0.5842)
			(end -1.2954 0.5842)
			(stroke
				(width 0.1524)
				(type default)
			)
			(layer "F.SilkS")
		)
		(fp_line
			(start 1.2954 -0.5842)
			(end 1.2954 0.5842)
			(stroke
				(width 0.1524)
				(type default)
			)
			(layer "F.SilkS")
		)
		(fp_line
			(start -1.2954 0.5842)
			(end -1.2954 -0.5842)
			(stroke
				(width 0.1524)
				(type default)
			)
			(layer "F.SilkS")
		)
		(fp_line
			(start -1.2954 -0.5842)
			(end 1.2954 -0.5842)
			(stroke
				(width 0.1524)
				(type default)
			)
			(layer "F.SilkS")
		)
		(fp_line
			(start 1.1938 0.4064)
			(end 0.8636 0.4064)
			(stroke
				(width 0.1)
				(type default)
			)
			(layer "F.Fab")
		)
		(fp_line
			(start 1.1938 -0.4064)
			(end 1.1938 0.4064)
			(stroke
				(width 0.1)
				(type default)
			)
			(layer "F.Fab")
		)
		(fp_line
			(start 0.8636 0.4572)
			(end -0.8636 0.4572)
			(stroke
				(width 0.1)
				(type default)
			)
			(layer "F.Fab")
		)
		(fp_line
			(start 0.8636 0.4064)
			(end 0.8636 0.4572)
			(stroke
				(width 0.1)
				(type default)
			)
			(layer "F.Fab")
		)
		(fp_line
			(start 0.8636 -0.4064)
			(end 1.1938 -0.4064)
			(stroke
				(width 0.1)
				(type default)
			)
			(layer "F.Fab")
		)
		(fp_line
			(start 0.8636 -0.4572)
			(end 0.8636 -0.4064)
			(stroke
				(width 0.1)
				(type default)
			)
			(layer "F.Fab")
		)
		(fp_line
			(start -0.8636 0.4572)
			(end -0.8636 0.4064)
			(stroke
				(width 0.1)
				(type default)
			)
			(layer "F.Fab")
		)
		(fp_line
			(start -0.8636 0.4064)
			(end -1.1938 0.4064)
			(stroke
				(width 0.1)
				(type default)
			)
			(layer "F.Fab")
		)
		(fp_line
			(start -0.8636 -0.4064)
			(end -0.8636 -0.4572)
			(stroke
				(width 0.1)
				(type default)
			)
			(layer "F.Fab")
		)
		(fp_line
			(start -0.8636 -0.4572)
			(end 0.8636 -0.4572)
			(stroke
				(width 0.1)
				(type default)
			)
			(layer "F.Fab")
		)
		(fp_line
			(start -1.1938 0.4064)
			(end -1.1938 -0.4064)
			(stroke
				(width 0.1)
				(type default)
			)
			(layer "F.Fab")
		)
		(fp_line
			(start -1.1938 -0.4064)
			(end -0.8636 -0.4064)
			(stroke
				(width 0.1)
				(type default)
			)
			(layer "F.Fab")
		)
		(pad "1" smd rect
			(at -0.7366 0 90)
			(size 0.7112 0.8128)
			(layers "F.Cu" "F.Mask" "F.Paste")
			(net "P1V8_CLI_VCORE")
		)
		(pad "2" smd rect
			(at 0.7366 0 90)
			(size 0.7112 0.8128)
			(layers "F.Cu" "F.Mask" "F.Paste")
			(net "GND")
		)
	)
	(footprint ""
		(layer "F.Cu")
		(at 270.799814 -151.279352 180)
		(property "Reference" "R220"
			(at 0 0 180)
			(layer "F.SilkS")
			(hide yes)
			(effects
				(font
					(size 1.27 1.27)
				)
			)
		)
		(property "Value" ""
			(at 0 0 180)
			(layer "F.Fab")
			(effects
				(font
					(size 1.27 1.27)
				)
			)
		)
		(duplicate_pad_numbers_are_jumpers no)
		(fp_line
			(start 0.7874 0.4064)
			(end -0.7874 0.4064)
			(stroke
				(width 0.1524)
				(type default)
			)
			(layer "F.SilkS")
		)
		(fp_line
			(start 0.7874 -0.4064)
			(end 0.7874 0.4064)
			(stroke
				(width 0.1524)
				(type default)
			)
			(layer "F.SilkS")
		)
		(fp_line
			(start -0.7874 0.4064)
			(end -0.7874 -0.4064)
			(stroke
				(width 0.1524)
				(type default)
			)
			(layer "F.SilkS")
		)
		(fp_line
			(start -0.7874 -0.4064)
			(end 0.7874 -0.4064)
			(stroke
				(width 0.1524)
				(type default)
			)
			(layer "F.SilkS")
		)
		(fp_line
			(start 0.67945 0.3048)
			(end 0.120396 0.3048)
			(stroke
				(width 0.1)
				(type default)
			)
			(layer "F.Fab")
		)
		(fp_line
			(start 0.67945 -0.3048)
			(end 0.67945 0.3048)
			(stroke
				(width 0.1)
				(type default)
			)
			(layer "F.Fab")
		)
		(fp_line
			(start 0.12065 -0.2794)
			(end 0.12065 -0.3048)
			(stroke
				(width 0.1)
				(type default)
			)
			(layer "F.Fab")
		)
		(fp_line
			(start 0.12065 -0.3048)
			(end 0.67945 -0.3048)
			(stroke
				(width 0.1)
				(type default)
			)
			(layer "F.Fab")
		)
		(fp_line
			(start 0.120396 0.3048)
			(end 0.120396 0.2794)
			(stroke
				(width 0.1)
				(type default)
			)
			(layer "F.Fab")
		)
		(fp_line
			(start 0.120396 0.2794)
			(end -0.12065 0.2794)
			(stroke
				(width 0.1)
				(type default)
			)
			(layer "F.Fab")
		)
		(fp_line
			(start -0.12065 0.3048)
			(end -0.67945 0.3048)
			(stroke
				(width 0.1)
				(type default)
			)
			(layer "F.Fab")
		)
		(fp_line
			(start -0.12065 0.2794)
			(end -0.12065 0.3048)
			(stroke
				(width 0.1)
				(type default)
			)
			(layer "F.Fab")
		)
		(fp_line
			(start -0.12065 -0.2794)
			(end 0.12065 -0.2794)
			(stroke
				(width 0.1)
				(type default)
			)
			(layer "F.Fab")
		)
		(fp_line
			(start -0.12065 -0.305054)
			(end -0.12065 -0.2794)
			(stroke
				(width 0.1)
				(type default)
			)
			(layer "F.Fab")
		)
		(fp_line
			(start -0.67945 0.3048)
			(end -0.67945 -0.305054)
			(stroke
				(width 0.1)
				(type default)
			)
			(layer "F.Fab")
		)
		(fp_line
			(start -0.67945 -0.305054)
			(end -0.12065 -0.305054)
			(stroke
				(width 0.1)
				(type default)
			)
			(layer "F.Fab")
		)
		(pad "1" smd circle
			(at -0.40005 0 180)
			(size 0 0)
			(layers "F.Cu" "F.Mask" "F.Paste")
			(net "NCSI_NIC4_RXD0")
		)
		(pad "2" smd circle
			(at 0.40005 0 180)
			(size 0 0)
			(layers "F.Cu" "F.Mask" "F.Paste")
			(net "GND")
		)
	)
	(footprint ""
		(layer "F.Cu")
		(at 46.44644 -58.323734)
		(property "Reference" "PC377"
			(at 0 0 0)
			(layer "F.SilkS")
			(hide yes)
			(effects
				(font
					(size 1.27 1.27)
				)
			)
		)
		(property "Value" ""
			(at 0 0 0)
			(layer "F.Fab")
			(effects
				(font
					(size 1.27 1.27)
				)
			)
		)
		(duplicate_pad_numbers_are_jumpers no)
		(fp_line
			(start -1.524 -0.762)
			(end 1.524 -0.762)
			(stroke
				(width 0.1524)
				(type default)
			)
			(layer "F.SilkS")
		)
		(fp_line
			(start -1.524 0.762)
			(end -1.524 -0.762)
			(stroke
				(width 0.1524)
				(type default)
			)
			(layer "F.SilkS")
		)
		(fp_line
			(start 1.524 -0.762)
			(end 1.524 0.762)
			(stroke
				(width 0.1524)
				(type default)
			)
			(layer "F.SilkS")
		)
		(fp_line
			(start 1.524 0.762)
			(end -1.524 0.762)
			(stroke
				(width 0.1524)
				(type default)
			)
			(layer "F.SilkS")
		)
		(fp_line
			(start -1.1049 -0.724916)
			(end -1.1049 0.724916)
			(stroke
				(width 0.1)
				(type default)
			)
			(layer "F.Fab")
		)
		(fp_line
			(start -1.1049 0.724916)
			(end 1.1049 0.724916)
			(stroke
				(width 0.1)
				(type default)
			)
			(layer "F.Fab")
		)
		(fp_line
			(start 1.1049 -0.724916)
			(end -1.1049 -0.724916)
			(stroke
				(width 0.1)
				(type default)
			)
			(layer "F.Fab")
		)
		(fp_line
			(start 1.1049 0.724916)
			(end 1.1049 -0.724916)
			(stroke
				(width 0.1)
				(type default)
			)
			(layer "F.Fab")
		)
		(pad "1" smd rect
			(at -0.889 0 180)
			(size 1.016 1.27)
			(layers "F.Cu" "F.Mask" "F.Paste")
			(net "GND")
		)
		(pad "2" smd rect
			(at 0.889 0 180)
			(size 1.016 1.27)
			(layers "F.Cu" "F.Mask" "F.Paste")
			(net "P12V_AUX")
		)
	)
	(footprint ""
		(layer "F.Cu")
		(at 20.901914 -413.969708 90)
		(property "Reference" "R5590"
			(at 0 0 90)
			(layer "F.SilkS")
			(hide yes)
			(effects
				(font
					(size 1.27 1.27)
				)
			)
		)
		(property "Value" ""
			(at 0 0 90)
			(layer "F.Fab")
			(effects
				(font
					(size 1.27 1.27)
				)
			)
		)
		(duplicate_pad_numbers_are_jumpers no)
		(fp_line
			(start 0.7874 -0.4064)
			(end 0.7874 0.4064)
			(stroke
				(width 0.1524)
				(type default)
			)
			(layer "F.SilkS")
		)
		(fp_line
			(start -0.7874 -0.4064)
			(end 0.7874 -0.4064)
			(stroke
				(width 0.1524)
				(type default)
			)
			(layer "F.SilkS")
		)
		(fp_line
			(start 0.7874 0.4064)
			(end -0.7874 0.4064)
			(stroke
				(width 0.1524)
				(type default)
			)
			(layer "F.SilkS")
		)
		(fp_line
			(start -0.7874 0.4064)
			(end -0.7874 -0.4064)
			(stroke
				(width 0.1524)
				(type default)
			)
			(layer "F.SilkS")
		)
		(fp_line
			(start -0.12065 -0.305054)
			(end -0.12065 -0.2794)
			(stroke
				(width 0.1)
				(type default)
			)
			(layer "F.Fab")
		)
		(fp_line
			(start -0.67945 -0.305054)
			(end -0.12065 -0.305054)
			(stroke
				(width 0.1)
				(type default)
			)
			(layer "F.Fab")
		)
		(fp_line
			(start 0.67945 -0.3048)
			(end 0.67945 0.3048)
			(stroke
				(width 0.1)
				(type default)
			)
			(layer "F.Fab")
		)
		(fp_line
			(start 0.12065 -0.3048)
			(end 0.67945 -0.3048)
			(stroke
				(width 0.1)
				(type default)
			)
			(layer "F.Fab")
		)
		(fp_line
			(start 0.12065 -0.2794)
			(end 0.12065 -0.3048)
			(stroke
				(width 0.1)
				(type default)
			)
			(layer "F.Fab")
		)
		(fp_line
			(start -0.12065 -0.2794)
			(end 0.12065 -0.2794)
			(stroke
				(width 0.1)
				(type default)
			)
			(layer "F.Fab")
		)
		(fp_line
			(start 0.120396 0.2794)
			(end -0.12065 0.2794)
			(stroke
				(width 0.1)
				(type default)
			)
			(layer "F.Fab")
		)
		(fp_line
			(start -0.12065 0.2794)
			(end -0.12065 0.3048)
			(stroke
				(width 0.1)
				(type default)
			)
			(layer "F.Fab")
		)
		(fp_line
			(start 0.67945 0.3048)
			(end 0.120396 0.3048)
			(stroke
				(width 0.1)
				(type default)
			)
			(layer "F.Fab")
		)
		(fp_line
			(start 0.120396 0.3048)
			(end 0.120396 0.2794)
			(stroke
				(width 0.1)
				(type default)
			)
			(layer "F.Fab")
		)
		(fp_line
			(start -0.12065 0.3048)
			(end -0.67945 0.3048)
			(stroke
				(width 0.1)
				(type default)
			)
			(layer "F.Fab")
		)
		(fp_line
			(start -0.67945 0.3048)
			(end -0.67945 -0.305054)
			(stroke
				(width 0.1)
				(type default)
			)
			(layer "F.Fab")
		)
		(pad "1" smd circle
			(at -0.40005 0 90)
			(size 0 0)
			(layers "F.Cu" "F.Mask" "F.Paste")
			(net "LM75_0_A2")
		)
		(pad "2" smd circle
			(at 0.40005 0 90)
			(size 0 0)
			(layers "F.Cu" "F.Mask" "F.Paste")
			(net "P3V3_AUX")
		)
	)
	(footprint ""
		(layer "F.Cu")
		(at 30.438344 -252.356874 -90)
		(property "Reference" "R1190"
			(at 0 0 270)
			(layer "F.SilkS")
			(hide yes)
			(effects
				(font
					(size 1.27 1.27)
				)
			)
		)
		(property "Value" ""
			(at 0 0 270)
			(layer "F.Fab")
			(effects
				(font
					(size 1.27 1.27)
				)
			)
		)
		(duplicate_pad_numbers_are_jumpers no)
		(fp_line
			(start -0.7874 0.4064)
			(end -0.7874 -0.4064)
			(stroke
				(width 0.1524)
				(type default)
			)
			(layer "F.SilkS")
		)
		(fp_line
			(start 0.7874 0.4064)
			(end -0.7874 0.4064)
			(stroke
				(width 0.1524)
				(type default)
			)
			(layer "F.SilkS")
		)
		(fp_line
			(start -0.7874 -0.4064)
			(end 0.7874 -0.4064)
			(stroke
				(width 0.1524)
				(type default)
			)
			(layer "F.SilkS")
		)
		(fp_line
			(start 0.7874 -0.4064)
			(end 0.7874 0.4064)
			(stroke
				(width 0.1524)
				(type default)
			)
			(layer "F.SilkS")
		)
		(fp_line
			(start -0.67945 0.3048)
			(end -0.67945 -0.305054)
			(stroke
				(width 0.1)
				(type default)
			)
			(layer "F.Fab")
		)
		(fp_line
			(start -0.12065 0.3048)
			(end -0.67945 0.3048)
			(stroke
				(width 0.1)
				(type default)
			)
			(layer "F.Fab")
		)
		(fp_line
			(start 0.120396 0.3048)
			(end 0.120396 0.2794)
			(stroke
				(width 0.1)
				(type default)
			)
			(layer "F.Fab")
		)
		(fp_line
			(start 0.67945 0.3048)
			(end 0.120396 0.3048)
			(stroke
				(width 0.1)
				(type default)
			)
			(layer "F.Fab")
		)
		(fp_line
			(start -0.12065 0.2794)
			(end -0.12065 0.3048)
			(stroke
				(width 0.1)
				(type default)
			)
			(layer "F.Fab")
		)
		(fp_line
			(start 0.120396 0.2794)
			(end -0.12065 0.2794)
			(stroke
				(width 0.1)
				(type default)
			)
			(layer "F.Fab")
		)
		(fp_line
			(start -0.12065 -0.2794)
			(end 0.12065 -0.2794)
			(stroke
				(width 0.1)
				(type default)
			)
			(layer "F.Fab")
		)
		(fp_line
			(start 0.12065 -0.2794)
			(end 0.12065 -0.3048)
			(stroke
				(width 0.1)
				(type default)
			)
			(layer "F.Fab")
		)
		(fp_line
			(start 0.12065 -0.3048)
			(end 0.67945 -0.3048)
			(stroke
				(width 0.1)
				(type default)
			)
			(layer "F.Fab")
		)
		(fp_line
			(start 0.67945 -0.3048)
			(end 0.67945 0.3048)
			(stroke
				(width 0.1)
				(type default)
			)
			(layer "F.Fab")
		)
		(fp_line
			(start -0.67945 -0.305054)
			(end -0.12065 -0.305054)
			(stroke
				(width 0.1)
				(type default)
			)
			(layer "F.Fab")
		)
		(fp_line
			(start -0.12065 -0.305054)
			(end -0.12065 -0.2794)
			(stroke
				(width 0.1)
				(type default)
			)
			(layer "F.Fab")
		)
		(pad "1" smd circle
			(at -0.40005 0 270)
			(size 0 0)
			(layers "F.Cu" "F.Mask" "F.Paste")
			(net "GND")
		)
		(pad "2" smd circle
			(at 0.40005 0 270)
			(size 0 0)
			(layers "F.Cu" "F.Mask" "F.Paste")
			(net "PEX0_MODE_SEL0")
		)
	)
)
